# BASEBOARD_FAB2 (Tioga Pass) — schematic netlist excerpt (pin names and nets, part order shuffled) for the footprints in the layout excerpt that follows; sources: Cadence DE-HDL packaged netlist, KiCad conversion of Wiwynn_Tioga_Pass_MB.brd

C4D27  CAP_A  1.0UF 6.3V 10% X6S  pkg 0402V  page 102 : A = P3V3_DB1200_R ; B = GND
C5G14  CAP_A  47UF 4V 20% X5R  pkg 0603V  page 217 : A = PVDDQ_ABC ; B = GND
C5A15  CAP_A  47UF 4V 20% X5R  pkg 0603V  page 220 : A = PVDDQ_DEF ; B = GND

(kicad_pcb
	(version 20260206)
	(generator "pcbnew")
	(generator_version "10.0")
	(general
		(thickness 1.6)
		(legacy_teardrops no)
	)
	(paper "A4")
	(title_block
		(title "Wiwynn_Tioga_Pass_MB.brd")
		(comment 1 "Tioga Pass / footprints 1127-1129 of 4770")
	)
	(layers
		(0 "F.Cu" signal "TOP")
		(4 "In1.Cu" signal "L2GND")
		(6 "In2.Cu" signal "L3")
		(8 "In3.Cu" signal "L4GND")
		(10 "In4.Cu" signal "L5")
		(12 "In5.Cu" signal "L6GND")
		(14 "In6.Cu" signal "L7VCC")
		(16 "In7.Cu" signal "L8VCC")
		(18 "In8.Cu" signal "L9GND")
		(20 "In9.Cu" signal "L10")
		(22 "In10.Cu" signal "L11GND")
		(24 "In11.Cu" signal "L12")
		(26 "In12.Cu" signal "L13GND")
		(2 "B.Cu" signal "BOTTOM")
		(9 "F.Adhes" user "F.Adhesive")
		(11 "B.Adhes" user "B.Adhesive")
		(13 "F.Paste" user "Package Geometry/Pastemask Top")
		(15 "B.Paste" user "Package Geometry/Pastemask Bottom")
		(5 "F.SilkS" user "Ref Des/Silkscreen Top")
		(7 "B.SilkS" user "Ref Des/Silkscreen Bottom")
		(1 "F.Mask" user "Board Geometry/Soldermask Top")
		(3 "B.Mask" user "Board Geometry/Soldermask Bottom")
		(17 "Dwgs.User" user "User.Drawings")
		(19 "Cmts.User" user "User.Comments")
		(21 "Eco1.User" user "User.Eco1")
		(23 "Eco2.User" user "User.Eco2")
		(25 "Edge.Cuts" user "Board Geometry/Outline")
		(27 "Margin" user)
		(31 "F.CrtYd" user "Package Geometry/Place Bound Top")
		(29 "B.CrtYd" user "Package Geometry/Place Bound Bottom")
		(35 "F.Fab" user "Ref Des/Assembly Top")
		(33 "B.Fab" user "Ref Des/Assembly Bottom")
	)
	(footprint ""
		(layer "F.Cu")
		(at 253.392432 -3.3528 90)
		(property "Reference" "C5G14"
			(at 1.848866 0.752348 90)
			(unlocked yes)
			(layer "F.SilkS")
			(effects
				(font
					(size 1.27 0.9652)
					(thickness 0.1524)
				)
			)
		)
		(property "Value" ""
			(at 0 0 90)
			(layer "F.Fab")
			(effects
				(font
					(size 1.27 1.27)
				)
			)
		)
		(duplicate_pad_numbers_are_jumpers no)
		(fp_rect
			(start -0.500126 1.598422)
			(end 0.500126 -0.201422)
			(stroke
				(width 0)
				(type default)
			)
			(fill no)
			(layer "F.CrtYd")
		)
		(fp_line
			(start 0.500126 -0.201422)
			(end 0.500126 1.598422)
			(stroke
				(width 0.1)
				(type default)
			)
			(layer "F.Fab")
		)
		(fp_line
			(start -0.500126 -0.201422)
			(end 0.500126 -0.201422)
			(stroke
				(width 0.1)
				(type default)
			)
			(layer "F.Fab")
		)
		(fp_line
			(start 0.500126 1.598422)
			(end -0.500126 1.598422)
			(stroke
				(width 0.1)
				(type default)
			)
			(layer "F.Fab")
		)
		(fp_line
			(start -0.500126 1.598422)
			(end -0.500126 -0.201422)
			(stroke
				(width 0.1)
				(type default)
			)
			(layer "F.Fab")
		)
		(pad "1" smd rect
			(at 0 0)
			(size 0.889 0.9906)
			(layers "F.Cu" "F.Mask" "F.Paste")
			(net "PVDDQ_ABC")
		)
		(pad "2" smd rect
			(at 0 1.397)
			(size 0.889 0.9906)
			(layers "F.Cu" "F.Mask" "F.Paste")
			(net "GND")
		)
		(zone
			(layer "F.Cu")
			(hatch none 0.5)
			(connect_pads
				(clearance 0)
			)
			(min_thickness 0.25)
			(keepout
				(tracks not_allowed)
				(vias allowed)
				(pads allowed)
				(copperpour not_allowed)
				(footprints allowed)
			)
			(placement
				(enabled no)
				(sheetname "")
			)
			(fill
				(thermal_gap 0.5)
				(thermal_bridge_width 0.5)
				(island_removal_mode 0)
			)
			(polygon
				(pts
					(xy 254.344932 -2.8575) (xy 254.344932 -3.8481) (xy 253.836932 -3.8481) (xy 253.836932 -2.8575)
				)
			)
		)
		(zone
			(layer "F.Cu")
			(hatch none 0.5)
			(connect_pads
				(clearance 0)
			)
			(min_thickness 0.25)
			(keepout
				(tracks allowed)
				(vias not_allowed)
				(pads allowed)
				(copperpour not_allowed)
				(footprints allowed)
			)
			(placement
				(enabled no)
				(sheetname "")
			)
			(fill
				(thermal_gap 0.5)
				(thermal_bridge_width 0.5)
				(island_removal_mode 0)
			)
			(polygon
				(pts
					(xy 254.344932 -2.8575) (xy 254.344932 -3.8481) (xy 253.836932 -3.8481) (xy 253.836932 -2.8575)
				)
			)
		)
	)
	(footprint ""
		(layer "F.Cu")
		(at 169.037 -73.7108 90)
		(property "Reference" "C4D27"
			(at 0 0 90)
			(layer "F.SilkS")
			(hide yes)
			(effects
				(font
					(size 1.27 1.27)
				)
			)
		)
		(property "Value" ""
			(at 0 0 90)
			(layer "F.Fab")
			(effects
				(font
					(size 1.27 1.27)
				)
			)
		)
		(duplicate_pad_numbers_are_jumpers no)
		(fp_poly
			(pts
				(xy 0.3048 -0.1016) (xy 0.3048 0.9906) (xy -0.3048 0.9906) (xy -0.3048 -0.1016)
			)
			(stroke
				(width 0)
				(type default)
			)
			(fill no)
			(layer "F.CrtYd")
		)
		(fp_line
			(start 0.3048 -0.1016)
			(end -0.3048 -0.1016)
			(stroke
				(width 0.1)
				(type default)
			)
			(layer "F.Fab")
		)
		(fp_line
			(start -0.3048 -0.1016)
			(end -0.3048 0.9906)
			(stroke
				(width 0.1)
				(type default)
			)
			(layer "F.Fab")
		)
		(fp_line
			(start 0.3048 0.9906)
			(end 0.3048 -0.1016)
			(stroke
				(width 0.1)
				(type default)
			)
			(layer "F.Fab")
		)
		(fp_line
			(start -0.3048 0.9906)
			(end 0.3048 0.9906)
			(stroke
				(width 0.1)
				(type default)
			)
			(layer "F.Fab")
		)
		(pad "1" smd rect
			(at 0 0 90)
			(size 0.508 0.508)
			(layers "F.Cu" "F.Mask" "F.Paste")
			(net "P3V3_DB1200_R")
		)
		(pad "2" smd rect
			(at 0 0.889 90)
			(size 0.508 0.508)
			(layers "F.Cu" "F.Mask" "F.Paste")
			(net "GND")
		)
		(zone
			(layer "F.Cu")
			(hatch none 0.5)
			(connect_pads
				(clearance 0)
			)
			(min_thickness 0.25)
			(keepout
				(tracks allowed)
				(vias not_allowed)
				(pads allowed)
				(copperpour not_allowed)
				(footprints allowed)
			)
			(placement
				(enabled no)
				(sheetname "")
			)
			(fill
				(thermal_gap 0.5)
				(thermal_bridge_width 0.5)
				(island_removal_mode 0)
			)
			(polygon
				(pts
					(xy 169.291 -73.4568) (xy 169.291 -73.9648) (xy 169.672 -73.9648) (xy 169.672 -73.4568)
				)
			)
		)
		(zone
			(layer "F.Cu")
			(hatch none 0.5)
			(connect_pads
				(clearance 0)
			)
			(min_thickness 0.25)
			(keepout
				(tracks not_allowed)
				(vias allowed)
				(pads allowed)
				(copperpour not_allowed)
				(footprints allowed)
			)
			(placement
				(enabled no)
				(sheetname "")
			)
			(fill
				(thermal_gap 0.5)
				(thermal_bridge_width 0.5)
				(island_removal_mode 0)
			)
			(polygon
				(pts
					(xy 169.672 -73.4568) (xy 169.672 -73.9648) (xy 169.291 -73.9648) (xy 169.291 -73.4568)
				)
			)
		)
	)
	(footprint ""
		(layer "F.Cu")
		(at 258.064 -140.1318 -90)
		(property "Reference" "C5A15"
			(at 1.848866 0.752348 270)
			(unlocked yes)
			(layer "F.SilkS")
			(effects
				(font
					(size 1.27 0.9652)
					(thickness 0.1524)
				)
			)
		)
		(property "Value" ""
			(at 0 0 270)
			(layer "F.Fab")
			(effects
				(font
					(size 1.27 1.27)
				)
			)
		)
		(duplicate_pad_numbers_are_jumpers no)
		(fp_rect
			(start -0.500126 1.598422)
			(end 0.500126 -0.201422)
			(stroke
				(width 0)
				(type default)
			)
			(fill no)
			(layer "F.CrtYd")
		)
		(fp_line
			(start -0.500126 1.598422)
			(end -0.500126 -0.201422)
			(stroke
				(width 0.1)
				(type default)
			)
			(layer "F.Fab")
		)
		(fp_line
			(start 0.500126 1.598422)
			(end -0.500126 1.598422)
			(stroke
				(width 0.1)
				(type default)
			)
			(layer "F.Fab")
		)
		(fp_line
			(start -0.500126 -0.201422)
			(end 0.500126 -0.201422)
			(stroke
				(width 0.1)
				(type default)
			)
			(layer "F.Fab")
		)
		(fp_line
			(start 0.500126 -0.201422)
			(end 0.500126 1.598422)
			(stroke
				(width 0.1)
				(type default)
			)
			(layer "F.Fab")
		)
		(pad "1" smd rect
			(at 0 0 180)
			(size 0.889 0.9906)
			(layers "F.Cu" "F.Mask" "F.Paste")
			(net "PVDDQ_DEF")
		)
		(pad "2" smd rect
			(at 0 1.397 180)
			(size 0.889 0.9906)
			(layers "F.Cu" "F.Mask" "F.Paste")
			(net "GND")
		)
		(zone
			(layer "F.Cu")
			(hatch none 0.5)
			(connect_pads
				(clearance 0)
			)
			(min_thickness 0.25)
			(keepout
				(tracks not_allowed)
				(vias allowed)
				(pads allowed)
				(copperpour not_allowed)
				(footprints allowed)
			)
			(placement
				(enabled no)
				(sheetname "")
			)
			(fill
				(thermal_gap 0.5)
				(thermal_bridge_width 0.5)
				(island_removal_mode 0)
			)
			(polygon
				(pts
					(xy 257.1115 -140.6271) (xy 257.1115 -139.6365) (xy 257.6195 -139.6365) (xy 257.6195 -140.6271)
				)
			)
		)
		(zone
			(layer "F.Cu")
			(hatch none 0.5)
			(connect_pads
				(clearance 0)
			)
			(min_thickness 0.25)
			(keepout
				(tracks allowed)
				(vias not_allowed)
				(pads allowed)
				(copperpour not_allowed)
				(footprints allowed)
			)
			(placement
				(enabled no)
				(sheetname "")
			)
			(fill
				(thermal_gap 0.5)
				(thermal_bridge_width 0.5)
				(island_removal_mode 0)
			)
			(polygon
				(pts
					(xy 257.1115 -140.6271) (xy 257.1115 -139.6365) (xy 257.6195 -139.6365) (xy 257.6195 -140.6271)
				)
			)
		)
	)
)
